(kicad_pcb
	(version 20260206)
	(generator "pcbnew")
	(generator_version "10.0")
	(general
		(thickness 1.6)
		(legacy_teardrops no)
	)
	(paper "A4")
	(title_block
		(title "01162023_DA0F0TEBIF0_F0T_Expander_BD_F_brd_V02_OCP.brd")
		(comment 1 "Grand Teton / footprints 9217-9226 of 9728")
	)
	(layers
		(0 "F.Cu" signal "TOP")
		(4 "In1.Cu" signal "GND")
		(6 "In2.Cu" signal "VCC")
		(8 "In3.Cu" signal "VCC1")
		(10 "In4.Cu" signal "GND1")
		(12 "In5.Cu" signal "IN1")
		(14 "In6.Cu" signal "GND2")
		(16 "In7.Cu" signal "IN2")
		(18 "In8.Cu" signal "GND3")
		(20 "In9.Cu" signal "IN3")
		(22 "In10.Cu" signal "GND4")
		(24 "In11.Cu" signal "IN4")
		(26 "In12.Cu" signal "GND5")
		(28 "In13.Cu" signal "IN5")
		(30 "In14.Cu" signal "GND6")
		(32 "In15.Cu" signal "IN6")
		(34 "In16.Cu" signal "GND7")
		(2 "B.Cu" signal "BOTTOM")
		(9 "F.Adhes" user "F.Adhesive")
		(11 "B.Adhes" user "B.Adhesive")
		(13 "F.Paste" user "Package Geometry/Pastemask Top")
		(15 "B.Paste" user "Package Geometry/Pastemask Bottom")
		(5 "F.SilkS" user "Ref Des/Silkscreen Top")
		(7 "B.SilkS" user "Ref Des/Silkscreen Bottom")
		(1 "F.Mask" user "Board Geometry/Soldermask Top")
		(3 "B.Mask" user "Board Geometry/Soldermask Bottom")
		(17 "Dwgs.User" user "User.Drawings")
		(19 "Cmts.User" user "User.Comments")
		(21 "Eco1.User" user "User.Eco1")
		(23 "Eco2.User" user "User.Eco2")
		(25 "Edge.Cuts" user "Board Geometry/Outline")
		(27 "Margin" user)
		(31 "F.CrtYd" user "Package Geometry/Place Bound Top")
		(29 "B.CrtYd" user "Package Geometry/Place Bound Bottom")
		(35 "F.Fab" user "Ref Des/Assembly Top")
		(33 "B.Fab" user "Ref Des/Assembly Bottom")
	)
	(footprint ""
		(layer "B.Cu")
		(at 205.148942 -259.311648 90)
		(property "Reference" "R6343"
			(at 0 0 90)
			(layer "B.SilkS")
			(hide yes)
			(effects
				(font
					(size 1.27 1.27)
				)
				(justify mirror)
			)
		)
		(property "Value" ""
			(at 0 0 90)
			(layer "B.Fab")
			(effects
				(font
					(size 1.27 1.27)
				)
				(justify mirror)
			)
		)
		(duplicate_pad_numbers_are_jumpers no)
		(fp_line
			(start 0.7874 -0.4064)
			(end -0.7874 -0.4064)
			(stroke
				(width 0.1524)
				(type default)
			)
			(layer "B.SilkS")
		)
		(fp_line
			(start -0.7874 -0.4064)
			(end -0.7874 0.4064)
			(stroke
				(width 0.1524)
				(type default)
			)
			(layer "B.SilkS")
		)
		(fp_line
			(start 0.7874 0.4064)
			(end 0.7874 -0.4064)
			(stroke
				(width 0.1524)
				(type default)
			)
			(layer "B.SilkS")
		)
		(fp_line
			(start -0.7874 0.4064)
			(end 0.7874 0.4064)
			(stroke
				(width 0.1524)
				(type default)
			)
			(layer "B.SilkS")
		)
		(fp_line
			(start 0.67945 -0.305054)
			(end 0.12065 -0.305054)
			(stroke
				(width 0.1)
				(type default)
			)
			(layer "B.Fab")
		)
		(fp_line
			(start 0.12065 -0.305054)
			(end 0.12065 -0.2794)
			(stroke
				(width 0.1)
				(type default)
			)
			(layer "B.Fab")
		)
		(fp_line
			(start -0.12065 -0.3048)
			(end -0.67945 -0.3048)
			(stroke
				(width 0.1)
				(type default)
			)
			(layer "B.Fab")
		)
		(fp_line
			(start -0.67945 -0.3048)
			(end -0.67945 0.3048)
			(stroke
				(width 0.1)
				(type default)
			)
			(layer "B.Fab")
		)
		(fp_line
			(start 0.12065 -0.2794)
			(end -0.12065 -0.2794)
			(stroke
				(width 0.1)
				(type default)
			)
			(layer "B.Fab")
		)
		(fp_line
			(start -0.12065 -0.2794)
			(end -0.12065 -0.3048)
			(stroke
				(width 0.1)
				(type default)
			)
			(layer "B.Fab")
		)
		(fp_line
			(start 0.12065 0.2794)
			(end 0.12065 0.3048)
			(stroke
				(width 0.1)
				(type default)
			)
			(layer "B.Fab")
		)
		(fp_line
			(start -0.120396 0.2794)
			(end 0.12065 0.2794)
			(stroke
				(width 0.1)
				(type default)
			)
			(layer "B.Fab")
		)
		(fp_line
			(start 0.67945 0.3048)
			(end 0.67945 -0.305054)
			(stroke
				(width 0.1)
				(type default)
			)
			(layer "B.Fab")
		)
		(fp_line
			(start 0.12065 0.3048)
			(end 0.67945 0.3048)
			(stroke
				(width 0.1)
				(type default)
			)
			(layer "B.Fab")
		)
		(fp_line
			(start -0.120396 0.3048)
			(end -0.120396 0.2794)
			(stroke
				(width 0.1)
				(type default)
			)
			(layer "B.Fab")
		)
		(fp_line
			(start -0.67945 0.3048)
			(end -0.120396 0.3048)
			(stroke
				(width 0.1)
				(type default)
			)
			(layer "B.Fab")
		)
		(pad "1" smd circle
			(at 0.40005 0 270)
			(size 0 0)
			(layers "B.Cu" "B.Mask" "B.Paste")
			(net "P1V8_PEX")
		)
		(pad "2" smd circle
			(at -0.40005 0 270)
			(size 0 0)
			(layers "B.Cu" "B.Mask" "B.Paste")
			(net "SMB_PEX0_MUX_SCL")
		)
	)
	(footprint ""
		(layer "B.Cu")
		(at 298.499784 -303.499774 -90)
		(property "Reference" "C3255"
			(at 0 0 90)
			(layer "B.SilkS")
			(hide yes)
			(effects
				(font
					(size 1.27 1.27)
				)
				(justify mirror)
			)
		)
		(property "Value" ""
			(at 0 0 90)
			(layer "B.Fab")
			(effects
				(font
					(size 1.27 1.27)
				)
				(justify mirror)
			)
		)
		(duplicate_pad_numbers_are_jumpers no)
		(fp_line
			(start -0.299974 0.150114)
			(end 0.299974 0.150114)
			(stroke
				(width 0.1)
				(type default)
			)
			(layer "B.Fab")
		)
		(fp_line
			(start 0.299974 0.150114)
			(end 0.299974 -0.150114)
			(stroke
				(width 0.1)
				(type default)
			)
			(layer "B.Fab")
		)
		(fp_line
			(start -0.299974 -0.150114)
			(end -0.299974 0.150114)
			(stroke
				(width 0.1)
				(type default)
			)
			(layer "B.Fab")
		)
		(fp_line
			(start 0.299974 -0.150114)
			(end -0.299974 -0.150114)
			(stroke
				(width 0.1)
				(type default)
			)
			(layer "B.Fab")
		)
		(pad "1" smd rect
			(at 0.2667 0 90)
			(size 0.3048 0.381)
			(layers "B.Cu" "B.Mask" "B.Paste")
			(net "P1V25_PEX2")
		)
		(pad "2" smd rect
			(at -0.2667 0 90)
			(size 0.3048 0.381)
			(layers "B.Cu" "B.Mask" "B.Paste")
			(net "GND")
		)
	)
	(footprint ""
		(layer "B.Cu")
		(at 357.887524 -261.179818)
		(property "Reference" "PR7143"
			(at 0 0 0)
			(layer "B.SilkS")
			(hide yes)
			(effects
				(font
					(size 1.27 1.27)
				)
				(justify mirror)
			)
		)
		(property "Value" ""
			(at 0 0 0)
			(layer "B.Fab")
			(effects
				(font
					(size 1.27 1.27)
				)
				(justify mirror)
			)
		)
		(duplicate_pad_numbers_are_jumpers no)
		(fp_line
			(start -0.7874 -0.4064)
			(end -0.7874 0.4064)
			(stroke
				(width 0.1524)
				(type default)
			)
			(layer "B.SilkS")
		)
		(fp_line
			(start -0.7874 0.4064)
			(end 0.7874 0.4064)
			(stroke
				(width 0.1524)
				(type default)
			)
			(layer "B.SilkS")
		)
		(fp_line
			(start 0.7874 -0.4064)
			(end -0.7874 -0.4064)
			(stroke
				(width 0.1524)
				(type default)
			)
			(layer "B.SilkS")
		)
		(fp_line
			(start 0.7874 0.4064)
			(end 0.7874 -0.4064)
			(stroke
				(width 0.1524)
				(type default)
			)
			(layer "B.SilkS")
		)
		(fp_line
			(start -0.67945 -0.3048)
			(end -0.67945 0.3048)
			(stroke
				(width 0.1)
				(type default)
			)
			(layer "B.Fab")
		)
		(fp_line
			(start -0.67945 0.3048)
			(end -0.120396 0.3048)
			(stroke
				(width 0.1)
				(type default)
			)
			(layer "B.Fab")
		)
		(fp_line
			(start -0.12065 -0.3048)
			(end -0.67945 -0.3048)
			(stroke
				(width 0.1)
				(type default)
			)
			(layer "B.Fab")
		)
		(fp_line
			(start -0.12065 -0.2794)
			(end -0.12065 -0.3048)
			(stroke
				(width 0.1)
				(type default)
			)
			(layer "B.Fab")
		)
		(fp_line
			(start -0.120396 0.2794)
			(end 0.12065 0.2794)
			(stroke
				(width 0.1)
				(type default)
			)
			(layer "B.Fab")
		)
		(fp_line
			(start -0.120396 0.3048)
			(end -0.120396 0.2794)
			(stroke
				(width 0.1)
				(type default)
			)
			(layer "B.Fab")
		)
		(fp_line
			(start 0.12065 -0.305054)
			(end 0.12065 -0.2794)
			(stroke
				(width 0.1)
				(type default)
			)
			(layer "B.Fab")
		)
		(fp_line
			(start 0.12065 -0.2794)
			(end -0.12065 -0.2794)
			(stroke
				(width 0.1)
				(type default)
			)
			(layer "B.Fab")
		)
		(fp_line
			(start 0.12065 0.2794)
			(end 0.12065 0.3048)
			(stroke
				(width 0.1)
				(type default)
			)
			(layer "B.Fab")
		)
		(fp_line
			(start 0.12065 0.3048)
			(end 0.67945 0.3048)
			(stroke
				(width 0.1)
				(type default)
			)
			(layer "B.Fab")
		)
		(fp_line
			(start 0.67945 -0.305054)
			(end 0.12065 -0.305054)
			(stroke
				(width 0.1)
				(type default)
			)
			(layer "B.Fab")
		)
		(fp_line
			(start 0.67945 0.3048)
			(end 0.67945 -0.305054)
			(stroke
				(width 0.1)
				(type default)
			)
			(layer "B.Fab")
		)
		(pad "1" smd circle
			(at 0.40005 0 180)
			(size 0 0)
			(layers "B.Cu" "B.Mask" "B.Paste")
			(net "GND")
		)
		(pad "2" smd circle
			(at -0.40005 0 180)
			(size 0 0)
			(layers "B.Cu" "B.Mask" "B.Paste")
			(net "P0V8_PEX2_SVID")
		)
	)
	(footprint ""
		(layer "B.Cu")
		(at 345.057476 -313.620404 180)
		(property "Reference" "L61"
			(at 0 0 0)
			(layer "B.SilkS")
			(hide yes)
			(effects
				(font
					(size 1.27 1.27)
				)
				(justify mirror)
			)
		)
		(property "Value" ""
			(at 0 0 0)
			(layer "B.Fab")
			(effects
				(font
					(size 1.27 1.27)
				)
				(justify mirror)
			)
		)
		(duplicate_pad_numbers_are_jumpers no)
		(fp_line
			(start 2.248154 4.9911)
			(end -2.248154 4.9911)
			(stroke
				(width 0.1524)
				(type default)
			)
			(layer "B.SilkS")
		)
		(fp_line
			(start 2.248154 1.658112)
			(end 2.248154 4.9911)
			(stroke
				(width 0.1524)
				(type default)
			)
			(layer "B.SilkS")
		)
		(fp_line
			(start 2.248154 -4.9911)
			(end 2.248154 -2.282952)
			(stroke
				(width 0.1524)
				(type default)
			)
			(layer "B.SilkS")
		)
		(fp_line
			(start -2.248154 4.9911)
			(end -2.248154 1.658112)
			(stroke
				(width 0.1524)
				(type default)
			)
			(layer "B.SilkS")
		)
		(fp_line
			(start -2.248154 -2.282952)
			(end -2.248154 -4.9911)
			(stroke
				(width 0.1524)
				(type default)
			)
			(layer "B.SilkS")
		)
		(fp_line
			(start -2.248154 -4.9911)
			(end 2.248154 -4.9911)
			(stroke
				(width 0.1524)
				(type default)
			)
			(layer "B.SilkS")
		)
		(fp_line
			(start 1.700022 0.899922)
			(end -1.700022 0.899922)
			(stroke
				(width 0.1)
				(type default)
			)
			(layer "B.Fab")
		)
		(fp_line
			(start 1.700022 -0.899922)
			(end 1.700022 0.899922)
			(stroke
				(width 0.1)
				(type default)
			)
			(layer "B.Fab")
		)
		(fp_line
			(start -1.700022 0.899922)
			(end -1.700022 -0.899922)
			(stroke
				(width 0.1)
				(type default)
			)
			(layer "B.Fab")
		)
		(fp_line
			(start -1.700022 -0.899922)
			(end 1.700022 -0.899922)
			(stroke
				(width 0.1)
				(type default)
			)
			(layer "B.Fab")
		)
		(pad "1" smd rect
			(at 1.575054 0)
			(size 1.1684 9.8044)
			(layers "B.Cu" "B.Mask" "B.Paste")
			(net "P0V8_PEX2")
		)
		(pad "2" smd rect
			(at -1.575054 0)
			(size 1.1684 9.8044)
			(layers "B.Cu" "B.Mask" "B.Paste")
			(net "P0V8_SERDES_VDDA_PEX2")
		)
	)
	(footprint ""
		(layer "B.Cu")
		(at 409.849828 -303.499774 -90)
		(property "Reference" "C3427"
			(at 0 0 90)
			(layer "B.SilkS")
			(hide yes)
			(effects
				(font
					(size 1.27 1.27)
				)
				(justify mirror)
			)
		)
		(property "Value" ""
			(at 0 0 90)
			(layer "B.Fab")
			(effects
				(font
					(size 1.27 1.27)
				)
				(justify mirror)
			)
		)
		(duplicate_pad_numbers_are_jumpers no)
		(fp_line
			(start -0.299974 0.150114)
			(end 0.299974 0.150114)
			(stroke
				(width 0.1)
				(type default)
			)
			(layer "B.Fab")
		)
		(fp_line
			(start 0.299974 0.150114)
			(end 0.299974 -0.150114)
			(stroke
				(width 0.1)
				(type default)
			)
			(layer "B.Fab")
		)
		(fp_line
			(start -0.299974 -0.150114)
			(end -0.299974 0.150114)
			(stroke
				(width 0.1)
				(type default)
			)
			(layer "B.Fab")
		)
		(fp_line
			(start 0.299974 -0.150114)
			(end -0.299974 -0.150114)
			(stroke
				(width 0.1)
				(type default)
			)
			(layer "B.Fab")
		)
		(pad "1" smd rect
			(at 0.2667 0 90)
			(size 0.3048 0.381)
			(layers "B.Cu" "B.Mask" "B.Paste")
			(net "P1V25_PEX3")
		)
		(pad "2" smd rect
			(at -0.2667 0 90)
			(size 0.3048 0.381)
			(layers "B.Cu" "B.Mask" "B.Paste")
			(net "GND")
		)
	)
	(footprint ""
		(layer "B.Cu")
		(at 410.799788 -299.699934 -90)
		(property "Reference" "C1992"
			(at 0 0 90)
			(layer "B.SilkS")
			(hide yes)
			(effects
				(font
					(size 1.27 1.27)
				)
				(justify mirror)
			)
		)
		(property "Value" ""
			(at 0 0 90)
			(layer "B.Fab")
			(effects
				(font
					(size 1.27 1.27)
				)
				(justify mirror)
			)
		)
		(duplicate_pad_numbers_are_jumpers no)
		(fp_line
			(start -0.299974 0.150114)
			(end 0.299974 0.150114)
			(stroke
				(width 0.1)
				(type default)
			)
			(layer "B.Fab")
		)
		(fp_line
			(start 0.299974 0.150114)
			(end 0.299974 -0.150114)
			(stroke
				(width 0.1)
				(type default)
			)
			(layer "B.Fab")
		)
		(fp_line
			(start -0.299974 -0.150114)
			(end -0.299974 0.150114)
			(stroke
				(width 0.1)
				(type default)
			)
			(layer "B.Fab")
		)
		(fp_line
			(start 0.299974 -0.150114)
			(end -0.299974 -0.150114)
			(stroke
				(width 0.1)
				(type default)
			)
			(layer "B.Fab")
		)
		(pad "1" smd rect
			(at 0.2667 0 90)
			(size 0.3048 0.381)
			(layers "B.Cu" "B.Mask" "B.Paste")
			(net "P0V8_SERDES_VDDA_PEX3")
		)
		(pad "2" smd rect
			(at -0.2667 0 90)
			(size 0.3048 0.381)
			(layers "B.Cu" "B.Mask" "B.Paste")
			(net "GND")
		)
	)
	(footprint ""
		(layer "B.Cu")
		(at 417.30422 -117.723666)
		(property "Reference" "C961"
			(at 0 0 0)
			(layer "B.SilkS")
			(hide yes)
			(effects
				(font
					(size 1.27 1.27)
				)
				(justify mirror)
			)
		)
		(property "Value" ""
			(at 0 0 0)
			(layer "B.Fab")
			(effects
				(font
					(size 1.27 1.27)
				)
				(justify mirror)
			)
		)
		(duplicate_pad_numbers_are_jumpers no)
		(fp_line
			(start -0.7874 -0.4064)
			(end -0.7874 0.4064)
			(stroke
				(width 0.1524)
				(type default)
			)
			(layer "B.SilkS")
		)
		(fp_line
			(start -0.7874 0.4064)
			(end 0.7874 0.4064)
			(stroke
				(width 0.1524)
				(type default)
			)
			(layer "B.SilkS")
		)
		(fp_line
			(start 0.7874 -0.4064)
			(end -0.7874 -0.4064)
			(stroke
				(width 0.1524)
				(type default)
			)
			(layer "B.SilkS")
		)
		(fp_line
			(start 0.7874 0.4064)
			(end 0.7874 -0.4064)
			(stroke
				(width 0.1524)
				(type default)
			)
			(layer "B.SilkS")
		)
		(fp_line
			(start -0.67945 -0.3048)
			(end -0.67945 0.3048)
			(stroke
				(width 0.1)
				(type default)
			)
			(layer "B.Fab")
		)
		(fp_line
			(start -0.67945 0.3048)
			(end -0.120396 0.3048)
			(stroke
				(width 0.1)
				(type default)
			)
			(layer "B.Fab")
		)
		(fp_line
			(start -0.12065 -0.3048)
			(end -0.67945 -0.3048)
			(stroke
				(width 0.1)
				(type default)
			)
			(layer "B.Fab")
		)
		(fp_line
			(start -0.12065 -0.2794)
			(end -0.12065 -0.3048)
			(stroke
				(width 0.1)
				(type default)
			)
			(layer "B.Fab")
		)
		(fp_line
			(start -0.120396 0.2794)
			(end 0.12065 0.2794)
			(stroke
				(width 0.1)
				(type default)
			)
			(layer "B.Fab")
		)
		(fp_line
			(start -0.120396 0.3048)
			(end -0.120396 0.2794)
			(stroke
				(width 0.1)
				(type default)
			)
			(layer "B.Fab")
		)
		(fp_line
			(start 0.12065 -0.305054)
			(end 0.12065 -0.2794)
			(stroke
				(width 0.1)
				(type default)
			)
			(layer "B.Fab")
		)
		(fp_line
			(start 0.12065 -0.2794)
			(end -0.12065 -0.2794)
			(stroke
				(width 0.1)
				(type default)
			)
			(layer "B.Fab")
		)
		(fp_line
			(start 0.12065 0.2794)
			(end 0.12065 0.3048)
			(stroke
				(width 0.1)
				(type default)
			)
			(layer "B.Fab")
		)
		(fp_line
			(start 0.12065 0.3048)
			(end 0.67945 0.3048)
			(stroke
				(width 0.1)
				(type default)
			)
			(layer "B.Fab")
		)
		(fp_line
			(start 0.67945 -0.305054)
			(end 0.12065 -0.305054)
			(stroke
				(width 0.1)
				(type default)
			)
			(layer "B.Fab")
		)
		(fp_line
			(start 0.67945 0.3048)
			(end 0.67945 -0.305054)
			(stroke
				(width 0.1)
				(type default)
			)
			(layer "B.Fab")
		)
		(pad "1" smd circle
			(at 0.40005 0 180)
			(size 0 0)
			(layers "B.Cu" "B.Mask" "B.Paste")
			(net "P3V3_AUX")
		)
		(pad "2" smd circle
			(at -0.40005 0 180)
			(size 0 0)
			(layers "B.Cu" "B.Mask" "B.Paste")
			(net "GND")
		)
	)
	(footprint ""
		(layer "B.Cu")
		(at 396.0749 -290.941506 90)
		(property "Reference" "C3582"
			(at 0 0 90)
			(layer "B.SilkS")
			(hide yes)
			(effects
				(font
					(size 1.27 1.27)
				)
				(justify mirror)
			)
		)
		(property "Value" ""
			(at 0 0 90)
			(layer "B.Fab")
			(effects
				(font
					(size 1.27 1.27)
				)
				(justify mirror)
			)
		)
		(duplicate_pad_numbers_are_jumpers no)
		(fp_line
			(start 0.299974 -0.150114)
			(end -0.299974 -0.150114)
			(stroke
				(width 0.1)
				(type default)
			)
			(layer "B.Fab")
		)
		(fp_line
			(start -0.299974 -0.150114)
			(end -0.299974 0.150114)
			(stroke
				(width 0.1)
				(type default)
			)
			(layer "B.Fab")
		)
		(fp_line
			(start 0.299974 0.150114)
			(end 0.299974 -0.150114)
			(stroke
				(width 0.1)
				(type default)
			)
			(layer "B.Fab")
		)
		(fp_line
			(start -0.299974 0.150114)
			(end 0.299974 0.150114)
			(stroke
				(width 0.1)
				(type default)
			)
			(layer "B.Fab")
		)
		(pad "1" smd rect
			(at 0.2667 0 270)
			(size 0.3048 0.381)
			(layers "B.Cu" "B.Mask" "B.Paste")
			(net "PCEPLL7_VDDA18_PEX3")
		)
		(pad "2" smd rect
			(at -0.2667 0 270)
			(size 0.3048 0.381)
			(layers "B.Cu" "B.Mask" "B.Paste")
			(net "GND")
		)
	)
	(footprint ""
		(layer "B.Cu")
		(at 44.449746 -293.99992)
		(property "Reference" "C2987"
			(at 0 0 0)
			(layer "B.SilkS")
			(hide yes)
			(effects
				(font
					(size 1.27 1.27)
				)
				(justify mirror)
			)
		)
		(property "Value" ""
			(at 0 0 0)
			(layer "B.Fab")
			(effects
				(font
					(size 1.27 1.27)
				)
				(justify mirror)
			)
		)
		(duplicate_pad_numbers_are_jumpers no)
		(fp_line
			(start -0.299974 -0.150114)
			(end -0.299974 0.150114)
			(stroke
				(width 0.1)
				(type default)
			)
			(layer "B.Fab")
		)
		(fp_line
			(start -0.299974 0.150114)
			(end 0.299974 0.150114)
			(stroke
				(width 0.1)
				(type default)
			)
			(layer "B.Fab")
		)
		(fp_line
			(start 0.299974 -0.150114)
			(end -0.299974 -0.150114)
			(stroke
				(width 0.1)
				(type default)
			)
			(layer "B.Fab")
		)
		(fp_line
			(start 0.299974 0.150114)
			(end 0.299974 -0.150114)
			(stroke
				(width 0.1)
				(type default)
			)
			(layer "B.Fab")
		)
		(pad "1" smd rect
			(at 0.2667 0 180)
			(size 0.3048 0.381)
			(layers "B.Cu" "B.Mask" "B.Paste")
			(net "P1V8_PEX")
		)
		(pad "2" smd rect
			(at -0.2667 0 180)
			(size 0.3048 0.381)
			(layers "B.Cu" "B.Mask" "B.Paste")
			(net "GND")
		)
	)
	(footprint ""
		(layer "B.Cu")
		(at 165.320218 -296.37482)
		(property "Reference" "C1391"
			(at 0 0 0)
			(layer "B.SilkS")
			(hide yes)
			(effects
				(font
					(size 1.27 1.27)
				)
				(justify mirror)
			)
		)
		(property "Value" ""
			(at 0 0 0)
			(layer "B.Fab")
			(effects
				(font
					(size 1.27 1.27)
				)
				(justify mirror)
			)
		)
		(duplicate_pad_numbers_are_jumpers no)
		(fp_line
			(start -0.299974 -0.150114)
			(end -0.299974 0.150114)
			(stroke
				(width 0.1)
				(type default)
			)
			(layer "B.Fab")
		)
		(fp_line
			(start -0.299974 0.150114)
			(end 0.299974 0.150114)
			(stroke
				(width 0.1)
				(type default)
			)
			(layer "B.Fab")
		)
		(fp_line
			(start 0.299974 -0.150114)
			(end -0.299974 -0.150114)
			(stroke
				(width 0.1)
				(type default)
			)
			(layer "B.Fab")
		)
		(fp_line
			(start 0.299974 0.150114)
			(end 0.299974 -0.150114)
			(stroke
				(width 0.1)
				(type default)
			)
			(layer "B.Fab")
		)
		(pad "1" smd rect
			(at 0.2667 0 180)
			(size 0.3048 0.381)
			(layers "B.Cu" "B.Mask" "B.Paste")
			(net "P0V8_PEX1")
		)
		(pad "2" smd rect
			(at -0.2667 0 180)
			(size 0.3048 0.381)
			(layers "B.Cu" "B.Mask" "B.Paste")
			(net "GND")
		)
	)
)
